G04*
G04 #@! TF.GenerationSoftware,Altium Limited,Altium Designer,23.7.1 (13)*
G04*
G04 Layer_Color=32768*
%FSLAX25Y25*%
%MOIN*%
G70*
G04*
G04 #@! TF.SameCoordinates,AF00DCEB-AC48-4C7C-91EA-99F42E284231*
G04*
G04*
G04 #@! TF.FilePolarity,Positive*
G04*
G01*
G75*
%ADD23C,0.00394*%
D23*
X148579Y-372099D02*
G03*
X134209Y-372099I-7185J0D01*
G01*
M02*
